(kicad_pcb
	(version 20260206)
	(generator "pcbnew")
	(generator_version "10.0")
	(general
		(thickness 1.6)
		(legacy_teardrops no)
	)
	(paper "A4")
	(title_block
		(title "netronome-mezz — pcbd0082-001_rev01_jul9_a.brd")
		(comment 1 "Open CloudServer (Microsoft) / footprint 225 of 714 (U1), pads 466-580 of 1022")
	)
	(layers
		(0 "F.Cu" signal "TOP")
		(4 "In1.Cu" signal "02_GND")
		(6 "In2.Cu" signal "03_SIG")
		(8 "In3.Cu" signal "04_SIG")
		(10 "In4.Cu" signal "05_GND")
		(12 "In5.Cu" signal "06_PWR1")
		(14 "In6.Cu" signal "07_SIG")
		(16 "In7.Cu" signal "08_SIG")
		(18 "In8.Cu" signal "09_GND")
		(2 "B.Cu" signal "BOTTOM")
		(9 "F.Adhes" user "F.Adhesive")
		(11 "B.Adhes" user "B.Adhesive")
		(13 "F.Paste" user "Package Geometry/Pastemask Top")
		(15 "B.Paste" user "Package Geometry/Pastemask Bottom")
		(5 "F.SilkS" user "Ref Des/Silkscreen Top")
		(7 "B.SilkS" user "Ref Des/Silkscreen Bottom")
		(1 "F.Mask" user "Board Geometry/Soldermask Top")
		(3 "B.Mask" user "Board Geometry/Soldermask Bottom")
		(17 "Dwgs.User" user "User.Drawings")
		(19 "Cmts.User" user "User.Comments")
		(21 "Eco1.User" user "User.Eco1")
		(23 "Eco2.User" user "User.Eco2")
		(25 "Edge.Cuts" user "Board Geometry/Outline")
		(27 "Margin" user)
		(31 "F.CrtYd" user "Package Geometry/Place Bound Top")
		(29 "B.CrtYd" user "Package Geometry/Place Bound Bottom")
		(35 "F.Fab" user "Ref Des/Assembly Top")
		(33 "B.Fab" user "Ref Des/Assembly Bottom")
		(45 "User.4" user "COMPVAL_TYPE_BOTTOM")
	)
	(footprint ""
		(layer "F.Cu")
		(at 54.737 18.542 180)
		(property "Reference" "U1"
			(at -12.192 17.9705 0)
			(unlocked yes)
			(layer "F.SilkS")
			(effects
				(font
					(size 1.27 0.9652)
					(thickness 0.1524)
				)
				(justify left)
			)
		)
		(property "Value" "*"
			(at -0.4826 1.74879 180)
			(unlocked yes)
			(layer "F.Fab")
			(hide yes)
			(effects
				(font
					(size 1.27 0.9652)
					(thickness 0.000001)
				)
				(justify left)
			)
		)
		(property "Device Type" "ICBG0048"
			(at -0.4826 1.74879 180)
			(unlocked yes)
			(layer "F.Fab")
			(hide yes)
			(effects
				(font
					(size 1.27 0.9652)
					(thickness 0.000001)
				)
				(justify left)
			)
		)
		(duplicate_pad_numbers_are_jumpers no)
		(pad "C20" smd circle
			(at 3.499993 -13.499998 180)
			(size 0.508 0.508)
			(layers "F.Cu" "F.Mask" "F.Paste")
			(net "GND")
		)
		(pad "C21" smd circle
			(at 4.499991 -13.499998 180)
			(size 0.508 0.508)
			(layers "F.Cu" "F.Mask" "F.Paste")
			(net "VDD_CORE")
		)
		(pad "C22" smd circle
			(at 5.499989 -13.499998 180)
			(size 0.508 0.508)
			(layers "F.Cu" "F.Mask" "F.Paste")
			(net "GND")
		)
		(pad "C23" smd circle
			(at 6.500012 -13.499998 180)
			(size 0.508 0.508)
			(layers "F.Cu" "F.Mask" "F.Paste")
			(net "VDD_CORE")
		)
		(pad "C24" smd circle
			(at 7.50001 -13.499998 180)
			(size 0.508 0.508)
			(layers "F.Cu" "F.Mask" "F.Paste")
			(net "GND")
		)
		(pad "C25" smd circle
			(at 8.500008 -13.499998 180)
			(size 0.508 0.508)
			(layers "F.Cu" "F.Mask" "F.Paste")
			(net "VDD_CORE")
		)
		(pad "C26" smd circle
			(at 9.500006 -13.499998 180)
			(size 0.508 0.508)
			(layers "F.Cu" "F.Mask" "F.Paste")
			(net "GND")
		)
		(pad "C27" smd circle
			(at 10.500004 -13.499998 180)
			(size 0.508 0.508)
			(layers "F.Cu" "F.Mask" "F.Paste")
			(net "_NC_TEST_SCAN_0_OUT37")
		)
		(pad "C28" smd circle
			(at 11.500002 -13.499998 180)
			(size 0.508 0.508)
			(layers "F.Cu" "F.Mask" "F.Paste")
			(net "_NC_TEST_SCAN_0_OUT29")
		)
		(pad "C29" smd circle
			(at 12.5 -13.499998 180)
			(size 0.508 0.508)
			(layers "F.Cu" "F.Mask" "F.Paste")
			(net "_NC_TEST_SCAN_0_OUT31")
		)
		(pad "C30" smd circle
			(at 13.499998 -13.499998 180)
			(size 0.508 0.508)
			(layers "F.Cu" "F.Mask" "F.Paste")
			(net "_NC_TEST_SCAN_0_OUT25")
		)
		(pad "C31" smd circle
			(at 14.499996 -13.499998 180)
			(size 0.508 0.508)
			(layers "F.Cu" "F.Mask" "F.Paste")
			(net "_NC_TEST_SCAN_0_OUT24")
		)
		(pad "C32" smd circle
			(at 15.499994 -13.499998 180)
			(size 0.6604 0.6604)
			(layers "F.Cu" "F.Mask" "F.Paste")
			(net "GND")
		)
		(pad "D1" smd circle
			(at -15.499994 -12.5 180)
			(size 0.508 0.508)
			(layers "F.Cu" "F.Mask" "F.Paste")
			(net "_NC_DDR0_32B_CB4")
		)
		(pad "D2" smd circle
			(at -14.499996 -12.5 180)
			(size 0.508 0.508)
			(layers "F.Cu" "F.Mask" "F.Paste")
			(net "_NC_DDR0_32B_CB3")
		)
		(pad "D3" smd circle
			(at -13.499998 -12.5 180)
			(size 0.508 0.508)
			(layers "F.Cu" "F.Mask" "F.Paste")
			(net "_NC_DDR0_32B_CB5")
		)
		(pad "D4" smd circle
			(at -12.5 -12.5 180)
			(size 0.508 0.508)
			(layers "F.Cu" "F.Mask" "F.Paste")
			(net "_NC_DDR0_32B_CB1")
		)
		(pad "D5" smd circle
			(at -11.500002 -12.5 180)
			(size 0.508 0.508)
			(layers "F.Cu" "F.Mask" "F.Paste")
			(net "_NC_DDR0_32B_CB6")
		)
		(pad "D6" smd circle
			(at -10.500004 -12.5 180)
			(size 0.508 0.508)
			(layers "F.Cu" "F.Mask" "F.Paste")
			(net "_NC_DDR0_32B_A15")
		)
		(pad "D7" smd circle
			(at -9.500006 -12.5 180)
			(size 0.508 0.508)
			(layers "F.Cu" "F.Mask" "F.Paste")
			(net "_NC_DDR0_32B_A10")
		)
		(pad "D8" smd circle
			(at -8.500008 -12.5 180)
			(size 0.508 0.508)
			(layers "F.Cu" "F.Mask" "F.Paste")
			(net "_NC_DDR0_32B_A13")
		)
		(pad "D9" smd circle
			(at -7.50001 -12.5 180)
			(size 0.508 0.508)
			(layers "F.Cu" "F.Mask" "F.Paste")
			(net "_NC_DDR0_32B_ODT1")
		)
		(pad "D10" smd circle
			(at -6.500012 -12.5 180)
			(size 0.508 0.508)
			(layers "F.Cu" "F.Mask" "F.Paste")
			(net "GND")
		)
		(pad "D11" smd circle
			(at -5.499989 -12.5 180)
			(size 0.508 0.508)
			(layers "F.Cu" "F.Mask" "F.Paste")
			(net "GND")
		)
		(pad "D12" smd circle
			(at -4.499991 -12.5 180)
			(size 0.508 0.508)
			(layers "F.Cu" "F.Mask" "F.Paste")
			(net "VDD_CORE")
		)
		(pad "D13" smd circle
			(at -3.499993 -12.5 180)
			(size 0.508 0.508)
			(layers "F.Cu" "F.Mask" "F.Paste")
			(net "GND")
		)
		(pad "D14" smd circle
			(at -2.499995 -12.5 180)
			(size 0.508 0.508)
			(layers "F.Cu" "F.Mask" "F.Paste")
			(net "VDD_CORE")
		)
		(pad "D15" smd circle
			(at -1.499997 -12.5 180)
			(size 0.508 0.508)
			(layers "F.Cu" "F.Mask" "F.Paste")
			(net "GND")
		)
		(pad "D16" smd circle
			(at -0.499999 -12.5 180)
			(size 0.508 0.508)
			(layers "F.Cu" "F.Mask" "F.Paste")
			(net "VDD_CORE")
		)
		(pad "D17" smd circle
			(at 0.499999 -12.5 180)
			(size 0.508 0.508)
			(layers "F.Cu" "F.Mask" "F.Paste")
			(net "GND")
		)
		(pad "D18" smd circle
			(at 1.499997 -12.5 180)
			(size 0.508 0.508)
			(layers "F.Cu" "F.Mask" "F.Paste")
			(net "VDD_CORE")
		)
		(pad "D19" smd circle
			(at 2.499995 -12.5 180)
			(size 0.508 0.508)
			(layers "F.Cu" "F.Mask" "F.Paste")
			(net "GND")
		)
		(pad "D20" smd circle
			(at 3.499993 -12.5 180)
			(size 0.508 0.508)
			(layers "F.Cu" "F.Mask" "F.Paste")
			(net "VDD_CORE")
		)
		(pad "D21" smd circle
			(at 4.499991 -12.5 180)
			(size 0.508 0.508)
			(layers "F.Cu" "F.Mask" "F.Paste")
			(net "GND")
		)
		(pad "D22" smd circle
			(at 5.499989 -12.5 180)
			(size 0.508 0.508)
			(layers "F.Cu" "F.Mask" "F.Paste")
			(net "VDD_CORE")
		)
		(pad "D23" smd circle
			(at 6.500012 -12.5 180)
			(size 0.508 0.508)
			(layers "F.Cu" "F.Mask" "F.Paste")
			(net "GND")
		)
		(pad "D24" smd circle
			(at 7.50001 -12.5 180)
			(size 0.508 0.508)
			(layers "F.Cu" "F.Mask" "F.Paste")
			(net "VDD_CORE")
		)
		(pad "D25" smd circle
			(at 8.500008 -12.5 180)
			(size 0.508 0.508)
			(layers "F.Cu" "F.Mask" "F.Paste")
			(net "GND")
		)
		(pad "D26" smd circle
			(at 9.500006 -12.5 180)
			(size 0.508 0.508)
			(layers "F.Cu" "F.Mask" "F.Paste")
			(net "VDD_CORE")
		)
		(pad "D27" smd circle
			(at 10.500004 -12.5 180)
			(size 0.508 0.508)
			(layers "F.Cu" "F.Mask" "F.Paste")
			(net "_NC_TEST_SCAN_0_OUT36")
		)
		(pad "D28" smd circle
			(at 11.500002 -12.5 180)
			(size 0.508 0.508)
			(layers "F.Cu" "F.Mask" "F.Paste")
			(net "GND")
		)
		(pad "D29" smd circle
			(at 12.5 -12.5 180)
			(size 0.508 0.508)
			(layers "F.Cu" "F.Mask" "F.Paste")
			(net "_NC_TEST_SCAN_0_OUT32")
		)
		(pad "D30" smd circle
			(at 13.499998 -12.5 180)
			(size 0.508 0.508)
			(layers "F.Cu" "F.Mask" "F.Paste")
			(net "_NC_TEST_SCAN_0_OUT23")
		)
		(pad "D31" smd circle
			(at 14.499996 -12.5 180)
			(size 0.508 0.508)
			(layers "F.Cu" "F.Mask" "F.Paste")
			(net "_NC_TEST_SCAN_0_OUT22")
		)
		(pad "D32" smd circle
			(at 15.499994 -12.5 180)
			(size 0.508 0.508)
			(layers "F.Cu" "F.Mask" "F.Paste")
			(net "_NC_TEST_SCAN_0_OUT26")
		)
		(pad "E1" smd circle
			(at -15.499994 -11.500002 180)
			(size 0.508 0.508)
			(layers "F.Cu" "F.Mask" "F.Paste")
			(net "_NC_DDR0_32B_DM4")
		)
		(pad "E2" smd circle
			(at -14.499996 -11.500002 180)
			(size 0.508 0.508)
			(layers "F.Cu" "F.Mask" "F.Paste")
			(net "_NC_DDR0_32B_CB2")
		)
		(pad "E3" smd circle
			(at -13.499998 -11.500002 180)
			(size 0.508 0.508)
			(layers "F.Cu" "F.Mask" "F.Paste")
			(net "_NC_DDR0_32B_DM3")
		)
		(pad "E4" smd circle
			(at -12.5 -11.500002 180)
			(size 0.508 0.508)
			(layers "F.Cu" "F.Mask" "F.Paste")
			(net "DDR_VDDQ")
		)
		(pad "E5" smd circle
			(at -11.500002 -11.500002 180)
			(size 0.508 0.508)
			(layers "F.Cu" "F.Mask" "F.Paste")
			(net "_NC_DDR0_32B_DQ30")
		)
		(pad "E6" smd circle
			(at -10.500004 -11.500002 180)
			(size 0.508 0.508)
			(layers "F.Cu" "F.Mask" "F.Paste")
			(net "_NC_DDR0_32B_A9")
		)
		(pad "E7" smd circle
			(at -9.500006 -11.500002 180)
			(size 0.508 0.508)
			(layers "F.Cu" "F.Mask" "F.Paste")
			(net "_NC_DDR0_32B_CKE0")
		)
		(pad "E8" smd circle
			(at -8.500008 -11.500002 180)
			(size 0.508 0.508)
			(layers "F.Cu" "F.Mask" "F.Paste")
			(net "DDR_VDDQ")
		)
		(pad "E9" smd circle
			(at -7.50001 -11.500002 180)
			(size 0.508 0.508)
			(layers "F.Cu" "F.Mask" "F.Paste")
			(net "_NC_DDR0_32B_CK0_N")
		)
		(pad "E10" smd circle
			(at -6.500012 -11.500002 180)
			(size 0.508 0.508)
			(layers "F.Cu" "F.Mask" "F.Paste")
			(net "GND")
		)
		(pad "E11" smd circle
			(at -5.499989 -11.500002 180)
			(size 0.508 0.508)
			(layers "F.Cu" "F.Mask" "F.Paste")
			(net "VDD_CORE")
		)
		(pad "E12" smd circle
			(at -4.499991 -11.500002 180)
			(size 0.508 0.508)
			(layers "F.Cu" "F.Mask" "F.Paste")
			(net "GND")
		)
		(pad "E13" smd circle
			(at -3.499993 -11.500002 180)
			(size 0.508 0.508)
			(layers "F.Cu" "F.Mask" "F.Paste")
			(net "VDD_CORE")
		)
		(pad "E14" smd circle
			(at -2.499995 -11.500002 180)
			(size 0.508 0.508)
			(layers "F.Cu" "F.Mask" "F.Paste")
			(net "GND")
		)
		(pad "E15" smd circle
			(at -1.499997 -11.500002 180)
			(size 0.508 0.508)
			(layers "F.Cu" "F.Mask" "F.Paste")
			(net "VDD_CORE")
		)
		(pad "E16" smd circle
			(at -0.499999 -11.500002 180)
			(size 0.508 0.508)
			(layers "F.Cu" "F.Mask" "F.Paste")
			(net "GND")
		)
		(pad "E17" smd circle
			(at 0.499999 -11.500002 180)
			(size 0.508 0.508)
			(layers "F.Cu" "F.Mask" "F.Paste")
			(net "VDD_CORE")
		)
		(pad "E18" smd circle
			(at 1.499997 -11.500002 180)
			(size 0.508 0.508)
			(layers "F.Cu" "F.Mask" "F.Paste")
			(net "GND")
		)
		(pad "E19" smd circle
			(at 2.499995 -11.500002 180)
			(size 0.508 0.508)
			(layers "F.Cu" "F.Mask" "F.Paste")
			(net "VDD_CORE")
		)
		(pad "E20" smd circle
			(at 3.499993 -11.500002 180)
			(size 0.508 0.508)
			(layers "F.Cu" "F.Mask" "F.Paste")
			(net "GND")
		)
		(pad "E21" smd circle
			(at 4.499991 -11.500002 180)
			(size 0.508 0.508)
			(layers "F.Cu" "F.Mask" "F.Paste")
			(net "VDD_CORE")
		)
		(pad "E22" smd circle
			(at 5.499989 -11.500002 180)
			(size 0.508 0.508)
			(layers "F.Cu" "F.Mask" "F.Paste")
			(net "GND")
		)
		(pad "E23" smd circle
			(at 6.500012 -11.500002 180)
			(size 0.508 0.508)
			(layers "F.Cu" "F.Mask" "F.Paste")
			(net "VDD_CORE")
		)
		(pad "E24" smd circle
			(at 7.50001 -11.500002 180)
			(size 0.508 0.508)
			(layers "F.Cu" "F.Mask" "F.Paste")
			(net "GND")
		)
		(pad "E25" smd circle
			(at 8.500008 -11.500002 180)
			(size 0.508 0.508)
			(layers "F.Cu" "F.Mask" "F.Paste")
			(net "VDD_CORE")
		)
		(pad "E26" smd circle
			(at 9.500006 -11.500002 180)
			(size 0.508 0.508)
			(layers "F.Cu" "F.Mask" "F.Paste")
			(net "GND")
		)
		(pad "E27" smd circle
			(at 10.500004 -11.500002 180)
			(size 0.508 0.508)
			(layers "F.Cu" "F.Mask" "F.Paste")
			(net "VDD_CORE")
		)
		(pad "E28" smd circle
			(at 11.500002 -11.500002 180)
			(size 0.508 0.508)
			(layers "F.Cu" "F.Mask" "F.Paste")
			(net "_NC_VDDQ_TEST_SCAN_0_OUT_1")
		)
		(pad "E29" smd circle
			(at 12.5 -11.500002 180)
			(size 0.508 0.508)
			(layers "F.Cu" "F.Mask" "F.Paste")
			(net "_NC_TEST_SCAN_0_OUT21")
		)
		(pad "E30" smd circle
			(at 13.499998 -11.500002 180)
			(size 0.508 0.508)
			(layers "F.Cu" "F.Mask" "F.Paste")
			(net "_NC_TEST_SCAN_0_OUT20")
		)
		(pad "E31" smd circle
			(at 14.499996 -11.500002 180)
			(size 0.508 0.508)
			(layers "F.Cu" "F.Mask" "F.Paste")
			(net "_NC_TEST_SCAN_0_OUT19")
		)
		(pad "E32" smd circle
			(at 15.499994 -11.500002 180)
			(size 0.508 0.508)
			(layers "F.Cu" "F.Mask" "F.Paste")
			(net "_NC_TEST_SCAN_0_OUT18")
		)
		(pad "F1" smd circle
			(at -15.499994 -10.500004 180)
			(size 0.508 0.508)
			(layers "F.Cu" "F.Mask" "F.Paste")
			(net "_NC_DDR0_32B_DQ27")
		)
		(pad "F2" smd circle
			(at -14.499996 -10.500004 180)
			(size 0.508 0.508)
			(layers "F.Cu" "F.Mask" "F.Paste")
			(net "_NC_DDR0_32B_DQ28")
		)
		(pad "F3" smd circle
			(at -13.499998 -10.500004 180)
			(size 0.508 0.508)
			(layers "F.Cu" "F.Mask" "F.Paste")
			(net "_NC_DDR0_32B_DQ29")
		)
		(pad "F4" smd circle
			(at -12.5 -10.500004 180)
			(size 0.508 0.508)
			(layers "F.Cu" "F.Mask" "F.Paste")
			(net "GND")
		)
		(pad "F5" smd circle
			(at -11.500002 -10.500004 180)
			(size 0.508 0.508)
			(layers "F.Cu" "F.Mask" "F.Paste")
			(net "_NC_DDR0_32B_DQ24")
		)
		(pad "F6" smd circle
			(at -10.500004 -10.500004 180)
			(size 0.508 0.508)
			(layers "F.Cu" "F.Mask" "F.Paste")
			(net "_NC_DDR0_32B_PAR_OUT")
		)
		(pad "F7" smd circle
			(at -9.500006 -10.500004 180)
			(size 0.508 0.508)
			(layers "F.Cu" "F.Mask" "F.Paste")
			(net "_NC_DDR0_32B_PAR_ERR_L")
		)
		(pad "F8" smd circle
			(at -8.500008 -10.500004 180)
			(size 0.508 0.508)
			(layers "F.Cu" "F.Mask" "F.Paste")
			(net "GND")
		)
		(pad "F9" smd circle
			(at -7.50001 -10.500004 180)
			(size 0.508 0.508)
			(layers "F.Cu" "F.Mask" "F.Paste")
			(net "_NC_DDR0_32B_CK0_P")
		)
		(pad "F10" smd circle
			(at -6.500012 -10.500004 180)
			(size 0.508 0.508)
			(layers "F.Cu" "F.Mask" "F.Paste")
			(net "GND")
		)
		(pad "F11" smd circle
			(at -5.499989 -10.500004 180)
			(size 0.508 0.508)
			(layers "F.Cu" "F.Mask" "F.Paste")
			(net "GND")
		)
		(pad "F12" smd circle
			(at -4.499991 -10.500004 180)
			(size 0.508 0.508)
			(layers "F.Cu" "F.Mask" "F.Paste")
			(net "VDD_CORE")
		)
		(pad "F13" smd circle
			(at -3.499993 -10.500004 180)
			(size 0.508 0.508)
			(layers "F.Cu" "F.Mask" "F.Paste")
			(net "GND")
		)
		(pad "F14" smd circle
			(at -2.499995 -10.500004 180)
			(size 0.508 0.508)
			(layers "F.Cu" "F.Mask" "F.Paste")
			(net "VDD_CORE")
		)
		(pad "F15" smd circle
			(at -1.499997 -10.500004 180)
			(size 0.508 0.508)
			(layers "F.Cu" "F.Mask" "F.Paste")
			(net "GND")
		)
		(pad "F16" smd circle
			(at -0.499999 -10.500004 180)
			(size 0.508 0.508)
			(layers "F.Cu" "F.Mask" "F.Paste")
			(net "VDD_CORE")
		)
		(pad "F17" smd circle
			(at 0.499999 -10.500004 180)
			(size 0.508 0.508)
			(layers "F.Cu" "F.Mask" "F.Paste")
			(net "GND")
		)
		(pad "F18" smd circle
			(at 1.499997 -10.500004 180)
			(size 0.508 0.508)
			(layers "F.Cu" "F.Mask" "F.Paste")
			(net "VDD_CORE")
		)
		(pad "F19" smd circle
			(at 2.499995 -10.500004 180)
			(size 0.508 0.508)
			(layers "F.Cu" "F.Mask" "F.Paste")
			(net "GND")
		)
		(pad "F20" smd circle
			(at 3.499993 -10.500004 180)
			(size 0.508 0.508)
			(layers "F.Cu" "F.Mask" "F.Paste")
			(net "VDD_CORE")
		)
		(pad "F21" smd circle
			(at 4.499991 -10.500004 180)
			(size 0.508 0.508)
			(layers "F.Cu" "F.Mask" "F.Paste")
			(net "GND")
		)
		(pad "F22" smd circle
			(at 5.499989 -10.500004 180)
			(size 0.508 0.508)
			(layers "F.Cu" "F.Mask" "F.Paste")
			(net "VDD_CORE")
		)
		(pad "F23" smd circle
			(at 6.500012 -10.500004 180)
			(size 0.508 0.508)
			(layers "F.Cu" "F.Mask" "F.Paste")
			(net "GND")
		)
		(pad "F24" smd circle
			(at 7.50001 -10.500004 180)
			(size 0.508 0.508)
			(layers "F.Cu" "F.Mask" "F.Paste")
			(net "VDD_CORE")
		)
		(pad "F25" smd circle
			(at 8.500008 -10.500004 180)
			(size 0.508 0.508)
			(layers "F.Cu" "F.Mask" "F.Paste")
			(net "GND")
		)
		(pad "F26" smd circle
			(at 9.500006 -10.500004 180)
			(size 0.508 0.508)
			(layers "F.Cu" "F.Mask" "F.Paste")
			(net "VDD_CORE")
		)
		(pad "F27" smd circle
			(at 10.500004 -10.500004 180)
			(size 0.508 0.508)
			(layers "F.Cu" "F.Mask" "F.Paste")
			(net "GND")
		)
		(pad "F28" smd circle
			(at 11.500002 -10.500004 180)
			(size 0.508 0.508)
			(layers "F.Cu" "F.Mask" "F.Paste")
			(net "_NC_TEST_SCAN_0_OUT16")
		)
		(pad "F29" smd circle
			(at 12.5 -10.500004 180)
			(size 0.508 0.508)
			(layers "F.Cu" "F.Mask" "F.Paste")
			(net "_NC_TEST_SCAN_0_OUT15")
		)
		(pad "F30" smd circle
			(at 13.499998 -10.500004 180)
			(size 0.508 0.508)
			(layers "F.Cu" "F.Mask" "F.Paste")
			(net "_NC_TEST_SCAN_0_OUT14")
		)
		(pad "F31" smd circle
			(at 14.499996 -10.500004 180)
			(size 0.508 0.508)
			(layers "F.Cu" "F.Mask" "F.Paste")
			(net "GND")
		)
		(pad "F32" smd circle
			(at 15.499994 -10.500004 180)
			(size 0.508 0.508)
			(layers "F.Cu" "F.Mask" "F.Paste")
			(net "_NC_TEST_SCAN_0_OUT13")
		)
		(pad "G1" smd circle
			(at -15.499994 -9.500006 180)
			(size 0.508 0.508)
			(layers "F.Cu" "F.Mask" "F.Paste")
			(net "_NC_DDR0_32B_DQ25")
		)
		(pad "G2" smd circle
			(at -14.499996 -9.500006 180)
			(size 0.508 0.508)
			(layers "F.Cu" "F.Mask" "F.Paste")
			(net "_NC_DDR0_32B_DQS3_N")
		)
		(pad "G3" smd circle
			(at -13.499998 -9.500006 180)
			(size 0.508 0.508)
			(layers "F.Cu" "F.Mask" "F.Paste")
			(net "_NC_DDR0_32B_DQS3_P")
		)
		(pad "G4" smd circle
			(at -12.5 -9.500006 180)
			(size 0.508 0.508)
			(layers "F.Cu" "F.Mask" "F.Paste")
			(net "_NC_DDR0_32B_DQ26")
		)
		(pad "G5" smd circle
			(at -11.500002 -9.500006 180)
			(size 0.508 0.508)
			(layers "F.Cu" "F.Mask" "F.Paste")
			(net "_NC_DDR0_32B_DQ31")
		)
		(pad "G6" smd circle
			(at -10.500004 -9.500006 180)
			(size 0.508 0.508)
			(layers "F.Cu" "F.Mask" "F.Paste")
			(net "_NC_DDR0_32B_A12")
		)
	)
)
